(kicad_pcb
	(version 20240108)
	(generator "pcbnew")
	(generator_version "8.0")
	(general
		(thickness 1.62)
		(legacy_teardrops no)
	)
	(paper "A4")
	(title_block
		(title "Jetson Orin Baseboard")
		(date "2025-03-12")
		(rev "1.3.4")
		(company "Antmicro Ltd")
		(comment 1 "www.antmicro.com")
		(comment 9 "footprints 648-652 of 677")
	)
	(layers
		(0 "F.Cu" signal)
		(1 "In1.Cu" signal)
		(2 "In2.Cu" signal)
		(3 "In3.Cu" signal)
		(4 "In4.Cu" jumper)
		(5 "In5.Cu" signal)
		(6 "In6.Cu" signal)
		(31 "B.Cu" signal)
		(32 "B.Adhes" user "B.Adhesive")
		(33 "F.Adhes" user "F.Adhesive")
		(34 "B.Paste" user)
		(35 "F.Paste" user)
		(36 "B.SilkS" user "B.Silkscreen")
		(37 "F.SilkS" user "F.Silkscreen")
		(38 "B.Mask" user)
		(39 "F.Mask" user)
		(40 "Dwgs.User" user "User.Drawings")
		(41 "Cmts.User" user "User.Comments")
		(42 "Eco1.User" user "User.Eco1")
		(43 "Eco2.User" user "User.Eco2")
		(44 "Edge.Cuts" user)
		(45 "Margin" user)
		(46 "B.CrtYd" user "B.Courtyard")
		(47 "F.CrtYd" user "F.Courtyard")
		(48 "B.Fab" user)
		(49 "F.Fab" user)
	)
	(footprint "antmicro-footprints:R_0402_1005Metric"
		(layer "B.Cu")
		(at 107.15175 95.525 90)
		(descr "Resistor SMD 0402")
		(tags "resistor SMD 0402")
		(property "Reference" "R174"
			(at 1.375 -0.40175 -90)
			(layer "B.SilkS")
			(effects
				(font
					(size 0.7 0.7)
					(thickness 0.15)
				)
				(justify left bottom mirror)
			)
		)
		(property "Value" "R_0R_0402"
			(at 0 -1.4 -90)
			(layer "B.Fab")
			(effects
				(font
					(size 0.7 0.7)
					(thickness 0.15)
				)
				(justify left bottom mirror)
			)
		)
		(property "Footprint" "antmicro-footprints:R_0402_1005Metric"
			(at 0 0 90)
			(layer "F.Fab")
			(hide yes)
			(effects
				(font
					(size 1.27 1.27)
					(thickness 0.15)
				)
			)
		)
		(property "Datasheet" "https://industrial.panasonic.com/cdbs/www-data/pdf/RDA0000/AOA0000C301.pdf"
			(at 0 0 90)
			(layer "F.Fab")
			(hide yes)
			(effects
				(font
					(size 1.27 1.27)
					(thickness 0.15)
				)
			)
		)
		(property "Author" "Antmicro"
			(at 202.67675 -11.62675 0)
			(layer "B.Fab")
			(hide yes)
			(effects
				(font
					(size 1 1)
					(thickness 0.15)
				)
				(justify mirror)
			)
		)
		(property "Current" "1A"
			(at 202.67675 -11.62675 0)
			(layer "B.Fab")
			(hide yes)
			(effects
				(font
					(size 1 1)
					(thickness 0.15)
				)
				(justify mirror)
			)
		)
		(property "License" "Apache-2.0"
			(at 202.67675 -11.62675 0)
			(layer "B.Fab")
			(hide yes)
			(effects
				(font
					(size 1 1)
					(thickness 0.15)
				)
				(justify mirror)
			)
		)
		(property "MPN" "ERJ2GE0R00X"
			(at 202.67675 -11.62675 0)
			(layer "B.Fab")
			(hide yes)
			(effects
				(font
					(size 1 1)
					(thickness 0.15)
				)
				(justify mirror)
			)
		)
		(property "Manufacturer" "Panasonic"
			(at 202.67675 -11.62675 0)
			(layer "B.Fab")
			(hide yes)
			(effects
				(font
					(size 1 1)
					(thickness 0.15)
				)
				(justify mirror)
			)
		)
		(property "Tolerance" ""
			(at 202.67675 -11.62675 0)
			(layer "B.Fab")
			(hide yes)
			(effects
				(font
					(size 1 1)
					(thickness 0.15)
				)
				(justify mirror)
			)
		)
		(property "Val" "0R"
			(at 202.67675 -11.62675 0)
			(layer "B.Fab")
			(hide yes)
			(effects
				(font
					(size 1 1)
					(thickness 0.15)
				)
				(justify mirror)
			)
		)
		(sheetname "CSI")
		(sheetfile "csi.kicad_sch")
		(attr smd)
		(fp_rect
			(start -0.925 0.47)
			(end 0.925 -0.47)
			(stroke
				(width 0.05)
				(type default)
			)
			(fill none)
			(layer "B.CrtYd")
		)
		(fp_rect
			(start -0.5 0.25)
			(end 0.5 -0.25)
			(stroke
				(width 0.15)
				(type solid)
			)
			(fill none)
			(layer "B.Fab")
		)
		(fp_text user "${REFERENCE}"
			(at -0.95 -3.168 -90)
			(layer "B.Fab")
			(hide yes)
			(effects
				(font
					(size 0.7 0.7)
					(thickness 0.15)
				)
				(justify left bottom mirror)
			)
		)
		(fp_text user "License: Apache-2.0"
			(at -0.95 -5.169 -90)
			(layer "B.Fab")
			(hide yes)
			(effects
				(font
					(size 0.7 0.7)
					(thickness 0.15)
				)
				(justify left bottom mirror)
			)
		)
		(fp_text user "Author: Antmicro"
			(at -0.95 -4.169 -90)
			(layer "B.Fab")
			(hide yes)
			(effects
				(font
					(size 0.7 0.7)
					(thickness 0.15)
				)
				(justify left bottom mirror)
			)
		)
		(pad "1" smd roundrect
			(at -0.48 0 90)
			(size 0.59 0.64)
			(layers "B.Cu" "B.Paste" "B.Mask")
			(roundrect_rratio 0.25)
			(net 636 "/CSI/CSIB_I2C_VCC")
			(pintype "passive")
		)
		(pad "2" smd roundrect
			(at 0.48 0 90)
			(size 0.59 0.64)
			(layers "B.Cu" "B.Paste" "B.Mask")
			(roundrect_rratio 0.25)
			(net 87 "+3V3")
			(pintype "passive")
		)
	)
	(footprint "antmicro-footprints:C_0402_1005Metric"
		(layer "B.Cu")
		(at 71.3 75.7 90)
		(descr "Capacitor SMD 0402")
		(tags "capacitor SMD 0402")
		(property "Reference" "C124"
			(at -2.27 14.38 -90)
			(layer "B.SilkS")
			(effects
				(font
					(size 0.7 0.7)
					(thickness 0.15)
				)
				(justify left bottom mirror)
			)
		)
		(property "Value" "C_100n_0402"
			(at 0 -1.4 -90)
			(layer "B.Fab")
			(effects
				(font
					(size 0.7 0.7)
					(thickness 0.15)
				)
				(justify left bottom mirror)
			)
		)
		(property "Footprint" "antmicro-footprints:C_0402_1005Metric"
			(at 0 0 90)
			(layer "F.Fab")
			(hide yes)
			(effects
				(font
					(size 1.27 1.27)
					(thickness 0.15)
				)
			)
		)
		(property "Datasheet" "https://www.murata.com/products/productdetail?partno=GRM155R61H104KE14%23"
			(at 0 0 90)
			(layer "F.Fab")
			(hide yes)
			(effects
				(font
					(size 1.27 1.27)
					(thickness 0.15)
				)
			)
		)
		(property "Author" "Antmicro"
			(at 147 4.4 0)
			(layer "B.Fab")
			(hide yes)
			(effects
				(font
					(size 1 1)
					(thickness 0.15)
				)
				(justify mirror)
			)
		)
		(property "Dielectric" "X5R"
			(at 147 4.4 0)
			(layer "B.Fab")
			(hide yes)
			(effects
				(font
					(size 1 1)
					(thickness 0.15)
				)
				(justify mirror)
			)
		)
		(property "License" "Apache-2.0"
			(at 147 4.4 0)
			(layer "B.Fab")
			(hide yes)
			(effects
				(font
					(size 1 1)
					(thickness 0.15)
				)
				(justify mirror)
			)
		)
		(property "MPN" "GRM155R61H104KE14D"
			(at 147 4.4 0)
			(layer "B.Fab")
			(hide yes)
			(effects
				(font
					(size 1 1)
					(thickness 0.15)
				)
				(justify mirror)
			)
		)
		(property "Manufacturer" "Murata"
			(at 147 4.4 0)
			(layer "B.Fab")
			(hide yes)
			(effects
				(font
					(size 1 1)
					(thickness 0.15)
				)
				(justify mirror)
			)
		)
		(property "Val" "100n"
			(at 147 4.4 0)
			(layer "B.Fab")
			(hide yes)
			(effects
				(font
					(size 1 1)
					(thickness 0.15)
				)
				(justify mirror)
			)
		)
		(property "Voltage" "50V"
			(at 147 4.4 0)
			(layer "B.Fab")
			(hide yes)
			(effects
				(font
					(size 1 1)
					(thickness 0.15)
				)
				(justify mirror)
			)
		)
		(sheetname "Supply")
		(sheetfile "supply.kicad_sch")
		(attr smd)
		(fp_rect
			(start -0.925 0.47)
			(end 0.925 -0.47)
			(stroke
				(width 0.05)
				(type default)
			)
			(fill none)
			(layer "B.CrtYd")
		)
		(fp_line
			(start 0.504 -0.248)
			(end 0.504 0.25)
			(stroke
				(width 0.15)
				(type solid)
			)
			(layer "B.Fab")
		)
		(fp_line
			(start -0.494 -0.248)
			(end 0.504 -0.248)
			(stroke
				(width 0.15)
				(type solid)
			)
			(layer "B.Fab")
		)
		(fp_line
			(start 0.504 0.25)
			(end -0.494 0.25)
			(stroke
				(width 0.15)
				(type solid)
			)
			(layer "B.Fab")
		)
		(fp_line
			(start -0.494 0.25)
			(end -0.494 -0.248)
			(stroke
				(width 0.15)
				(type solid)
			)
			(layer "B.Fab")
		)
		(fp_text user "Author: Antmicro"
			(at -0.932 -4.17 -90)
			(layer "B.Fab")
			(hide yes)
			(effects
				(font
					(size 0.7 0.7)
					(thickness 0.15)
				)
				(justify left bottom mirror)
			)
		)
		(fp_text user "License: Apache-2.0"
			(at -0.932 -5.17 -90)
			(layer "B.Fab")
			(hide yes)
			(effects
				(font
					(size 0.7 0.7)
					(thickness 0.15)
				)
				(justify left bottom mirror)
			)
		)
		(fp_text user "${REFERENCE}"
			(at -0.932 -3.168 -90)
			(layer "B.Fab")
			(hide yes)
			(effects
				(font
					(size 0.7 0.7)
					(thickness 0.15)
				)
				(justify left bottom mirror)
			)
		)
		(pad "1" smd roundrect
			(at -0.48 0 90)
			(size 0.59 0.64)
			(layers "B.Cu" "B.Paste" "B.Mask")
			(roundrect_rratio 0.25)
			(net 1 "GND")
			(pintype "passive")
		)
		(pad "2" smd roundrect
			(at 0.48 0 90)
			(size 0.59 0.64)
			(layers "B.Cu" "B.Paste" "B.Mask")
			(roundrect_rratio 0.25)
			(net 179 "Net-(D61-A)")
			(pintype "passive")
		)
	)
	(footprint "antmicro-footprints:C_0402_1005Metric"
		(layer "B.Cu")
		(at 73.5 107.2)
		(descr "Capacitor SMD 0402")
		(tags "capacitor SMD 0402")
		(property "Reference" "C58"
			(at -0.15 2.28 180)
			(layer "B.SilkS")
			(effects
				(font
					(size 0.7 0.7)
					(thickness 0.15)
				)
				(justify left bottom mirror)
			)
		)
		(property "Value" "C_100n_0402"
			(at 0 -1.4 180)
			(layer "B.Fab")
			(effects
				(font
					(size 0.7 0.7)
					(thickness 0.15)
				)
				(justify left bottom mirror)
			)
		)
		(property "Footprint" "antmicro-footprints:C_0402_1005Metric"
			(at 0 0 0)
			(layer "F.Fab")
			(hide yes)
			(effects
				(font
					(size 1.27 1.27)
					(thickness 0.15)
				)
			)
		)
		(property "Datasheet" "https://www.murata.com/products/productdetail?partno=GRM155R61H104KE14%23"
			(at 0 0 0)
			(layer "F.Fab")
			(hide yes)
			(effects
				(font
					(size 1.27 1.27)
					(thickness 0.15)
				)
			)
		)
		(property "Author" "Antmicro"
			(at 0 0 0)
			(layer "B.Fab")
			(hide yes)
			(effects
				(font
					(size 1 1)
					(thickness 0.15)
				)
				(justify mirror)
			)
		)
		(property "Dielectric" "X5R"
			(at 0 0 0)
			(layer "B.Fab")
			(hide yes)
			(effects
				(font
					(size 1 1)
					(thickness 0.15)
				)
				(justify mirror)
			)
		)
		(property "License" "Apache-2.0"
			(at 0 0 0)
			(layer "B.Fab")
			(hide yes)
			(effects
				(font
					(size 1 1)
					(thickness 0.15)
				)
				(justify mirror)
			)
		)
		(property "MPN" "GRM155R61H104KE14D"
			(at 0 0 0)
			(layer "B.Fab")
			(hide yes)
			(effects
				(font
					(size 1 1)
					(thickness 0.15)
				)
				(justify mirror)
			)
		)
		(property "Manufacturer" "Murata"
			(at 0 0 0)
			(layer "B.Fab")
			(hide yes)
			(effects
				(font
					(size 1 1)
					(thickness 0.15)
				)
				(justify mirror)
			)
		)
		(property "Val" "100n"
			(at 0 0 0)
			(layer "B.Fab")
			(hide yes)
			(effects
				(font
					(size 1 1)
					(thickness 0.15)
				)
				(justify mirror)
			)
		)
		(property "Voltage" "50V"
			(at 0 0 0)
			(layer "B.Fab")
			(hide yes)
			(effects
				(font
					(size 1 1)
					(thickness 0.15)
				)
				(justify mirror)
			)
		)
		(sheetname "USB Debug, DP")
		(sheetfile "usb.kicad_sch")
		(attr smd)
		(fp_rect
			(start -0.925 0.47)
			(end 0.925 -0.47)
			(stroke
				(width 0.05)
				(type default)
			)
			(fill none)
			(layer "B.CrtYd")
		)
		(fp_line
			(start -0.494 -0.248)
			(end 0.504 -0.248)
			(stroke
				(width 0.15)
				(type solid)
			)
			(layer "B.Fab")
		)
		(fp_line
			(start -0.494 0.25)
			(end -0.494 -0.248)
			(stroke
				(width 0.15)
				(type solid)
			)
			(layer "B.Fab")
		)
		(fp_line
			(start 0.504 -0.248)
			(end 0.504 0.25)
			(stroke
				(width 0.15)
				(type solid)
			)
			(layer "B.Fab")
		)
		(fp_line
			(start 0.504 0.25)
			(end -0.494 0.25)
			(stroke
				(width 0.15)
				(type solid)
			)
			(layer "B.Fab")
		)
		(fp_text user "License: Apache-2.0"
			(at -0.932 -5.17 180)
			(layer "B.Fab")
			(hide yes)
			(effects
				(font
					(size 0.7 0.7)
					(thickness 0.15)
				)
				(justify left bottom mirror)
			)
		)
		(fp_text user "${REFERENCE}"
			(at -0.932 -3.168 180)
			(layer "B.Fab")
			(hide yes)
			(effects
				(font
					(size 0.7 0.7)
					(thickness 0.15)
				)
				(justify left bottom mirror)
			)
		)
		(fp_text user "Author: Antmicro"
			(at -0.932 -4.17 180)
			(layer "B.Fab")
			(hide yes)
			(effects
				(font
					(size 0.7 0.7)
					(thickness 0.15)
				)
				(justify left bottom mirror)
			)
		)
		(pad "1" smd roundrect
			(at -0.48 0)
			(size 0.59 0.64)
			(layers "B.Cu" "B.Paste" "B.Mask")
			(roundrect_rratio 0.25)
			(net 481 "USBPD2_HV")
			(pintype "passive")
		)
		(pad "2" smd roundrect
			(at 0.48 0)
			(size 0.59 0.64)
			(layers "B.Cu" "B.Paste" "B.Mask")
			(roundrect_rratio 0.25)
			(net 1 "GND")
			(pintype "passive")
		)
	)
	(footprint "antmicro-footprints:R_0402_1005Metric"
		(layer "B.Cu")
		(at 61.8 78.95)
		(descr "Resistor SMD 0402")
		(tags "resistor SMD 0402")
		(property "Reference" "R258"
			(at 1.9 1.25 180)
			(layer "B.SilkS")
			(effects
				(font
					(size 0.7 0.7)
					(thickness 0.15)
				)
				(justify left bottom mirror)
			)
		)
		(property "Value" "R_200k_0402"
			(at 0 -1.4 180)
			(layer "B.Fab")
			(effects
				(font
					(size 0.7 0.7)
					(thickness 0.15)
				)
				(justify left bottom mirror)
			)
		)
		(property "Footprint" "antmicro-footprints:R_0402_1005Metric"
			(at 0 0 0)
			(layer "F.Fab")
			(hide yes)
			(effects
				(font
					(size 1.27 1.27)
					(thickness 0.15)
				)
			)
		)
		(property "Datasheet" "https://www.bourns.com/docs/product-datasheets/cr.pdf"
			(at 0 0 0)
			(layer "F.Fab")
			(hide yes)
			(effects
				(font
					(size 1.27 1.27)
					(thickness 0.15)
				)
			)
		)
		(property "Author" "Antmicro"
			(at 0 0 0)
			(layer "B.Fab")
			(hide yes)
			(effects
				(font
					(size 1 1)
					(thickness 0.15)
				)
				(justify mirror)
			)
		)
		(property "License" "Apache-2.0"
			(at 0 0 0)
			(layer "B.Fab")
			(hide yes)
			(effects
				(font
					(size 1 1)
					(thickness 0.15)
				)
				(justify mirror)
			)
		)
		(property "MPN" "CR0402-FX-2003GLF"
			(at 0 0 0)
			(layer "B.Fab")
			(hide yes)
			(effects
				(font
					(size 1 1)
					(thickness 0.15)
				)
				(justify mirror)
			)
		)
		(property "Manufacturer" "Bourns"
			(at 0 0 0)
			(layer "B.Fab")
			(hide yes)
			(effects
				(font
					(size 1 1)
					(thickness 0.15)
				)
				(justify mirror)
			)
		)
		(property "Tolerance" "1%"
			(at 0 0 0)
			(layer "B.Fab")
			(hide yes)
			(effects
				(font
					(size 1 1)
					(thickness 0.15)
				)
				(justify mirror)
			)
		)
		(property "Val" "200k"
			(at 0 0 0)
			(layer "B.Fab")
			(hide yes)
			(effects
				(font
					(size 1 1)
					(thickness 0.15)
				)
				(justify mirror)
			)
		)
		(sheetname "Supply")
		(sheetfile "supply.kicad_sch")
		(attr smd)
		(fp_rect
			(start -0.925 0.47)
			(end 0.925 -0.47)
			(stroke
				(width 0.05)
				(type default)
			)
			(fill none)
			(layer "B.CrtYd")
		)
		(fp_rect
			(start -0.5 0.25)
			(end 0.5 -0.25)
			(stroke
				(width 0.15)
				(type solid)
			)
			(fill none)
			(layer "B.Fab")
		)
		(fp_text user "${REFERENCE}"
			(at -0.95 -3.168 180)
			(layer "B.Fab")
			(hide yes)
			(effects
				(font
					(size 0.7 0.7)
					(thickness 0.15)
				)
				(justify left bottom mirror)
			)
		)
		(fp_text user "Author: Antmicro"
			(at -0.95 -4.169 180)
			(layer "B.Fab")
			(hide yes)
			(effects
				(font
					(size 0.7 0.7)
					(thickness 0.15)
				)
				(justify left bottom mirror)
			)
		)
		(fp_text user "License: Apache-2.0"
			(at -0.95 -5.169 180)
			(layer "B.Fab")
			(hide yes)
			(effects
				(font
					(size 0.7 0.7)
					(thickness 0.15)
				)
				(justify left bottom mirror)
			)
		)
		(pad "1" smd roundrect
			(at -0.48 0)
			(size 0.59 0.64)
			(layers "B.Cu" "B.Paste" "B.Mask")
			(roundrect_rratio 0.25)
			(net 137 "Net-(D36-A)")
			(pintype "passive")
		)
		(pad "2" smd roundrect
			(at 0.48 0)
			(size 0.59 0.64)
			(layers "B.Cu" "B.Paste" "B.Mask")
			(roundrect_rratio 0.25)
			(net 688 "Net-(U38-CLK)")
			(pintype "passive")
		)
	)
	(footprint "antmicro-footprints:C_0805_2012Metric"
		(layer "B.Cu")
		(at 62.675 92.95)
		(descr "Capacitor SMD 0805")
		(tags "capacitor SMD 0805")
		(property "Reference" "C5"
			(at -0.715 1 0)
			(layer "B.SilkS")
			(effects
				(font
					(size 0.7 0.7)
					(thickness 0.15)
				)
				(justify right top mirror)
			)
		)
		(property "Value" "C_22u_25V_0805"
			(at -2.055717 -1.963152 0)
			(layer "B.Fab")
			(effects
				(font
					(size 0.7 0.7)
					(thickness 0.15)
				)
				(justify right top mirror)
			)
		)
		(property "Footprint" "antmicro-footprints:C_0805_2012Metric"
			(at 0 0 0)
			(layer "B.Fab")
			(hide yes)
			(effects
				(font
					(size 1.27 1.27)
					(thickness 0.15)
				)
				(justify mirror)
			)
		)
		(property "Datasheet" "https://product.samsungsem.com/mlcc/CL21A226MAYNNN.do"
			(at 0 0 0)
			(layer "B.Fab")
			(hide yes)
			(effects
				(font
					(size 1.27 1.27)
					(thickness 0.15)
				)
				(justify mirror)
			)
		)
		(property "Author" "Antmicro"
			(at 0 0 0)
			(layer "B.Fab")
			(hide yes)
			(effects
				(font
					(size 1 1)
					(thickness 0.15)
				)
				(justify mirror)
			)
		)
		(property "Dielectric" "X5R"
			(at 0 0 0)
			(layer "B.Fab")
			(hide yes)
			(effects
				(font
					(size 1 1)
					(thickness 0.15)
				)
				(justify mirror)
			)
		)
		(property "License" "Apache-2.0"
			(at 0 0 0)
			(layer "B.Fab")
			(hide yes)
			(effects
				(font
					(size 1 1)
					(thickness 0.15)
				)
				(justify mirror)
			)
		)
		(property "MPN" "CL21A226MAYNNNE"
			(at 0 0 0)
			(layer "B.Fab")
			(hide yes)
			(effects
				(font
					(size 1 1)
					(thickness 0.15)
				)
				(justify mirror)
			)
		)
		(property "Manufacturer" "Samsung Electro-Mechanics"
			(at 0 0 0)
			(layer "B.Fab")
			(hide yes)
			(effects
				(font
					(size 1 1)
					(thickness 0.15)
				)
				(justify mirror)
			)
		)
		(property "Public" "False"
			(at 0 0 0)
			(layer "B.Fab")
			(hide yes)
			(effects
				(font
					(size 1 1)
					(thickness 0.15)
				)
				(justify mirror)
			)
		)
		(property "Val" "22u"
			(at 0 0 0)
			(layer "B.Fab")
			(hide yes)
			(effects
				(font
					(size 1 1)
					(thickness 0.15)
				)
				(justify mirror)
			)
		)
		(property "Voltage" "25V"
			(at 0 0 0)
			(layer "B.Fab")
			(hide yes)
			(effects
				(font
					(size 1 1)
					(thickness 0.15)
				)
				(justify mirror)
			)
		)
		(sheetname "Supply")
		(sheetfile "supply.kicad_sch")
		(attr smd)
		(fp_line
			(start 0.3 -0.7)
			(end -0.3 -0.7)
			(stroke
				(width 0.15)
				(type solid)
			)
			(layer "B.SilkS")
		)
		(fp_line
			(start 0.3 0.7)
			(end -0.3 0.7)
			(stroke
				(width 0.15)
				(type solid)
			)
			(layer "B.SilkS")
		)
		(fp_rect
			(start 1.95 0.9)
			(end -1.95 -0.9)
			(stroke
				(width 0.05)
				(type default)
			)
			(fill none)
			(layer "B.CrtYd")
		)
		(fp_rect
			(start -0.95 0.675)
			(end 0.95 -0.675)
			(stroke
				(width 0.15)
				(type solid)
			)
			(fill none)
			(layer "B.Fab")
		)
		(fp_text user "License: Apache-2.0"
			(at -1.9 -4.947 0)
			(layer "B.Fab")
			(hide yes)
			(effects
				(font
					(size 0.7 0.7)
					(thickness 0.15)
				)
				(justify right top mirror)
			)
		)
		(fp_text user "Author: Antmicro"
			(at -1.9 -5.947 0)
			(layer "B.Fab")
			(hide yes)
			(effects
				(font
					(size 0.7 0.7)
					(thickness 0.15)
				)
				(justify right top mirror)
			)
		)
		(fp_text user "${REFERENCE}"
			(at -1.9 -3.947 0)
			(layer "B.Fab")
			(hide yes)
			(effects
				(font
					(size 0.7 0.7)
					(thickness 0.15)
				)
				(justify right top mirror)
			)
		)
		(pad "1" smd roundrect
			(at -1.1 0)
			(size 1.2 1.3)
			(layers "B.Cu" "B.Paste" "B.Mask")
			(roundrect_rratio 0.25)
			(net 1 "GND")
			(pintype "passive")
		)
		(pad "2" smd roundrect
			(at 1.1 0)
			(size 1.2 1.3)
			(layers "B.Cu" "B.Paste" "B.Mask")
			(roundrect_rratio 0.25)
			(net 115 "VCC")
			(pintype "passive")
		)
	)
)
